(kicad_pcb
	(version 20260206)
	(generator "pcbnew")
	(generator_version "10.0")
	(general
		(thickness 1.6)
		(legacy_teardrops no)
	)
	(paper "A4")
	(title_block
		(title "04192023_DAF0TMB3IC0_F0TG_MB_C_brd_V02_OCP.brd")
		(comment 1 "Grand Teton / footprints 3120-3126 of 8354")
	)
	(layers
		(0 "F.Cu" signal "TOP")
		(4 "In1.Cu" signal "GND")
		(6 "In2.Cu" signal "IN1")
		(8 "In3.Cu" signal "GND1")
		(10 "In4.Cu" signal "IN2")
		(12 "In5.Cu" signal "GND2")
		(14 "In6.Cu" signal "IN3")
		(16 "In7.Cu" signal "GND3")
		(18 "In8.Cu" signal "VCC")
		(20 "In9.Cu" signal "VCC1")
		(22 "In10.Cu" signal "GND4")
		(24 "In11.Cu" signal "IN4")
		(26 "In12.Cu" signal "GND5")
		(28 "In13.Cu" signal "IN5")
		(30 "In14.Cu" signal "GND6")
		(32 "In15.Cu" signal "IN6")
		(34 "In16.Cu" signal "GND7")
		(2 "B.Cu" signal "BOTTOM")
		(9 "F.Adhes" user "F.Adhesive")
		(11 "B.Adhes" user "B.Adhesive")
		(13 "F.Paste" user "Package Geometry/Pastemask Top")
		(15 "B.Paste" user "Package Geometry/Pastemask Bottom")
		(5 "F.SilkS" user "Ref Des/Silkscreen Top")
		(7 "B.SilkS" user "Ref Des/Silkscreen Bottom")
		(1 "F.Mask" user "Board Geometry/Soldermask Top")
		(3 "B.Mask" user "Board Geometry/Soldermask Bottom")
		(17 "Dwgs.User" user "User.Drawings")
		(19 "Cmts.User" user "User.Comments")
		(21 "Eco1.User" user "User.Eco1")
		(23 "Eco2.User" user "User.Eco2")
		(25 "Edge.Cuts" user "Board Geometry/Outline")
		(27 "Margin" user)
		(31 "F.CrtYd" user "Package Geometry/Place Bound Top")
		(29 "B.CrtYd" user "Package Geometry/Place Bound Bottom")
		(35 "F.Fab" user "Ref Des/Assembly Top")
		(33 "B.Fab" user "Ref Des/Assembly Bottom")
	)
	(footprint ""
		(layer "F.Cu")
		(at 85.96757 -182.745634 90)
		(property "Reference" "PC258_C0P1_1"
			(at 0 0 90)
			(layer "F.SilkS")
			(hide yes)
			(effects
				(font
					(size 1.27 1.27)
				)
			)
		)
		(property "Value" ""
			(at 0 0 90)
			(layer "F.Fab")
			(effects
				(font
					(size 1.27 1.27)
				)
			)
		)
		(duplicate_pad_numbers_are_jumpers no)
		(fp_line
			(start 0.7874 -0.4064)
			(end 0.7874 0.4064)
			(stroke
				(width 0.1524)
				(type default)
			)
			(layer "F.SilkS")
		)
		(fp_line
			(start -0.7874 -0.4064)
			(end 0.7874 -0.4064)
			(stroke
				(width 0.1524)
				(type default)
			)
			(layer "F.SilkS")
		)
		(fp_line
			(start 0.7874 0.4064)
			(end -0.7874 0.4064)
			(stroke
				(width 0.1524)
				(type default)
			)
			(layer "F.SilkS")
		)
		(fp_line
			(start -0.7874 0.4064)
			(end -0.7874 -0.4064)
			(stroke
				(width 0.1524)
				(type default)
			)
			(layer "F.SilkS")
		)
		(fp_line
			(start -0.12065 -0.305054)
			(end -0.12065 -0.2794)
			(stroke
				(width 0.1)
				(type default)
			)
			(layer "F.Fab")
		)
		(fp_line
			(start -0.67945 -0.305054)
			(end -0.12065 -0.305054)
			(stroke
				(width 0.1)
				(type default)
			)
			(layer "F.Fab")
		)
		(fp_line
			(start 0.67945 -0.3048)
			(end 0.67945 0.3048)
			(stroke
				(width 0.1)
				(type default)
			)
			(layer "F.Fab")
		)
		(fp_line
			(start 0.12065 -0.3048)
			(end 0.67945 -0.3048)
			(stroke
				(width 0.1)
				(type default)
			)
			(layer "F.Fab")
		)
		(fp_line
			(start 0.12065 -0.2794)
			(end 0.12065 -0.3048)
			(stroke
				(width 0.1)
				(type default)
			)
			(layer "F.Fab")
		)
		(fp_line
			(start -0.12065 -0.2794)
			(end 0.12065 -0.2794)
			(stroke
				(width 0.1)
				(type default)
			)
			(layer "F.Fab")
		)
		(fp_line
			(start 0.120396 0.2794)
			(end -0.12065 0.2794)
			(stroke
				(width 0.1)
				(type default)
			)
			(layer "F.Fab")
		)
		(fp_line
			(start -0.12065 0.2794)
			(end -0.12065 0.3048)
			(stroke
				(width 0.1)
				(type default)
			)
			(layer "F.Fab")
		)
		(fp_line
			(start 0.67945 0.3048)
			(end 0.120396 0.3048)
			(stroke
				(width 0.1)
				(type default)
			)
			(layer "F.Fab")
		)
		(fp_line
			(start 0.120396 0.3048)
			(end 0.120396 0.2794)
			(stroke
				(width 0.1)
				(type default)
			)
			(layer "F.Fab")
		)
		(fp_line
			(start -0.12065 0.3048)
			(end -0.67945 0.3048)
			(stroke
				(width 0.1)
				(type default)
			)
			(layer "F.Fab")
		)
		(fp_line
			(start -0.67945 0.3048)
			(end -0.67945 -0.305054)
			(stroke
				(width 0.1)
				(type default)
			)
			(layer "F.Fab")
		)
		(pad "1" smd circle
			(at -0.40005 0 90)
			(size 0 0)
			(layers "F.Cu" "F.Mask" "F.Paste")
			(net "PVDDCR_CPU0_P1_PVCC")
		)
		(pad "2" smd circle
			(at 0.40005 0 90)
			(size 0 0)
			(layers "F.Cu" "F.Mask" "F.Paste")
			(net "GND")
		)
	)
	(footprint ""
		(layer "F.Cu")
		(at 131.425696 -373.03583 -90)
		(property "Reference" "C1524"
			(at 0 0 270)
			(layer "F.SilkS")
			(hide yes)
			(effects
				(font
					(size 1.27 1.27)
				)
			)
		)
		(property "Value" ""
			(at 0 0 270)
			(layer "F.Fab")
			(effects
				(font
					(size 1.27 1.27)
				)
			)
		)
		(duplicate_pad_numbers_are_jumpers no)
		(fp_line
			(start -0.299974 0.150114)
			(end -0.299974 -0.150114)
			(stroke
				(width 0.1)
				(type default)
			)
			(layer "F.Fab")
		)
		(fp_line
			(start 0.299974 0.150114)
			(end -0.299974 0.150114)
			(stroke
				(width 0.1)
				(type default)
			)
			(layer "F.Fab")
		)
		(fp_line
			(start -0.299974 -0.150114)
			(end 0.299974 -0.150114)
			(stroke
				(width 0.1)
				(type default)
			)
			(layer "F.Fab")
		)
		(fp_line
			(start 0.299974 -0.150114)
			(end 0.299974 0.150114)
			(stroke
				(width 0.1)
				(type default)
			)
			(layer "F.Fab")
		)
		(pad "1" smd rect
			(at -0.2667 0 270)
			(size 0.3048 0.381)
			(layers "F.Cu" "F.Mask" "F.Paste")
			(net "P5E_CPU1_P3_TX_C_DN<11>")
		)
		(pad "2" smd rect
			(at 0.2667 0 270)
			(size 0.3048 0.381)
			(layers "F.Cu" "F.Mask" "F.Paste")
			(net "P5E_CPU1_P3_TX_DN<11>")
		)
	)
	(footprint ""
		(layer "F.Cu")
		(at 168.144444 -370.57203 -90)
		(property "Reference" "C747"
			(at 0 0 270)
			(layer "F.SilkS")
			(hide yes)
			(effects
				(font
					(size 1.27 1.27)
				)
			)
		)
		(property "Value" ""
			(at 0 0 270)
			(layer "F.Fab")
			(effects
				(font
					(size 1.27 1.27)
				)
			)
		)
		(duplicate_pad_numbers_are_jumpers no)
		(fp_line
			(start -0.299974 0.150114)
			(end -0.299974 -0.150114)
			(stroke
				(width 0.1)
				(type default)
			)
			(layer "F.Fab")
		)
		(fp_line
			(start 0.299974 0.150114)
			(end -0.299974 0.150114)
			(stroke
				(width 0.1)
				(type default)
			)
			(layer "F.Fab")
		)
		(fp_line
			(start -0.299974 -0.150114)
			(end 0.299974 -0.150114)
			(stroke
				(width 0.1)
				(type default)
			)
			(layer "F.Fab")
		)
		(fp_line
			(start 0.299974 -0.150114)
			(end 0.299974 0.150114)
			(stroke
				(width 0.1)
				(type default)
			)
			(layer "F.Fab")
		)
		(pad "1" smd rect
			(at -0.2667 0 270)
			(size 0.3048 0.381)
			(layers "F.Cu" "F.Mask" "F.Paste")
			(net "P5E_CPU1_P2_TX_C_DP<13>")
		)
		(pad "2" smd rect
			(at 0.2667 0 270)
			(size 0.3048 0.381)
			(layers "F.Cu" "F.Mask" "F.Paste")
			(net "P5E_CPU1_P2_TX_DP<13>")
		)
	)
	(footprint ""
		(layer "F.Cu")
		(at 452.13905 -49.377346 180)
		(property "Reference" "PR835"
			(at 0 0 180)
			(layer "F.SilkS")
			(hide yes)
			(effects
				(font
					(size 1.27 1.27)
				)
			)
		)
		(property "Value" ""
			(at 0 0 180)
			(layer "F.Fab")
			(effects
				(font
					(size 1.27 1.27)
				)
			)
		)
		(duplicate_pad_numbers_are_jumpers no)
		(fp_line
			(start 0.7874 0.4064)
			(end -0.7874 0.4064)
			(stroke
				(width 0.1524)
				(type default)
			)
			(layer "F.SilkS")
		)
		(fp_line
			(start 0.7874 -0.4064)
			(end 0.7874 0.4064)
			(stroke
				(width 0.1524)
				(type default)
			)
			(layer "F.SilkS")
		)
		(fp_line
			(start -0.7874 0.4064)
			(end -0.7874 -0.4064)
			(stroke
				(width 0.1524)
				(type default)
			)
			(layer "F.SilkS")
		)
		(fp_line
			(start -0.7874 -0.4064)
			(end 0.7874 -0.4064)
			(stroke
				(width 0.1524)
				(type default)
			)
			(layer "F.SilkS")
		)
		(fp_line
			(start 0.67945 0.3048)
			(end 0.120396 0.3048)
			(stroke
				(width 0.1)
				(type default)
			)
			(layer "F.Fab")
		)
		(fp_line
			(start 0.67945 -0.3048)
			(end 0.67945 0.3048)
			(stroke
				(width 0.1)
				(type default)
			)
			(layer "F.Fab")
		)
		(fp_line
			(start 0.12065 -0.2794)
			(end 0.12065 -0.3048)
			(stroke
				(width 0.1)
				(type default)
			)
			(layer "F.Fab")
		)
		(fp_line
			(start 0.12065 -0.3048)
			(end 0.67945 -0.3048)
			(stroke
				(width 0.1)
				(type default)
			)
			(layer "F.Fab")
		)
		(fp_line
			(start 0.120396 0.3048)
			(end 0.120396 0.2794)
			(stroke
				(width 0.1)
				(type default)
			)
			(layer "F.Fab")
		)
		(fp_line
			(start 0.120396 0.2794)
			(end -0.12065 0.2794)
			(stroke
				(width 0.1)
				(type default)
			)
			(layer "F.Fab")
		)
		(fp_line
			(start -0.12065 0.3048)
			(end -0.67945 0.3048)
			(stroke
				(width 0.1)
				(type default)
			)
			(layer "F.Fab")
		)
		(fp_line
			(start -0.12065 0.2794)
			(end -0.12065 0.3048)
			(stroke
				(width 0.1)
				(type default)
			)
			(layer "F.Fab")
		)
		(fp_line
			(start -0.12065 -0.2794)
			(end 0.12065 -0.2794)
			(stroke
				(width 0.1)
				(type default)
			)
			(layer "F.Fab")
		)
		(fp_line
			(start -0.12065 -0.305054)
			(end -0.12065 -0.2794)
			(stroke
				(width 0.1)
				(type default)
			)
			(layer "F.Fab")
		)
		(fp_line
			(start -0.67945 0.3048)
			(end -0.67945 -0.305054)
			(stroke
				(width 0.1)
				(type default)
			)
			(layer "F.Fab")
		)
		(fp_line
			(start -0.67945 -0.305054)
			(end -0.12065 -0.305054)
			(stroke
				(width 0.1)
				(type default)
			)
			(layer "F.Fab")
		)
		(pad "1" smd circle
			(at -0.40005 0 180)
			(size 0 0)
			(layers "F.Cu" "F.Mask" "F.Paste")
			(net "SW_P3V3_AUX_BOOT")
		)
		(pad "2" smd circle
			(at 0.40005 0 180)
			(size 0 0)
			(layers "F.Cu" "F.Mask" "F.Paste")
			(net "SW_P3V3_AUX_BOOT_R")
		)
	)
	(footprint ""
		(layer "F.Cu")
		(at 423.610024 -363.78261)
		(property "Reference" "PC5"
			(at 0 0 0)
			(layer "F.SilkS")
			(hide yes)
			(effects
				(font
					(size 1.27 1.27)
				)
			)
		)
		(property "Value" ""
			(at 0 0 0)
			(layer "F.Fab")
			(effects
				(font
					(size 1.27 1.27)
				)
			)
		)
		(duplicate_pad_numbers_are_jumpers no)
		(fp_line
			(start -0.7874 -0.4064)
			(end 0.7874 -0.4064)
			(stroke
				(width 0.1524)
				(type default)
			)
			(layer "F.SilkS")
		)
		(fp_line
			(start -0.7874 0.4064)
			(end -0.7874 -0.4064)
			(stroke
				(width 0.1524)
				(type default)
			)
			(layer "F.SilkS")
		)
		(fp_line
			(start 0.7874 -0.4064)
			(end 0.7874 0.4064)
			(stroke
				(width 0.1524)
				(type default)
			)
			(layer "F.SilkS")
		)
		(fp_line
			(start 0.7874 0.4064)
			(end -0.7874 0.4064)
			(stroke
				(width 0.1524)
				(type default)
			)
			(layer "F.SilkS")
		)
		(fp_line
			(start -0.67945 -0.305054)
			(end -0.12065 -0.305054)
			(stroke
				(width 0.1)
				(type default)
			)
			(layer "F.Fab")
		)
		(fp_line
			(start -0.67945 0.3048)
			(end -0.67945 -0.305054)
			(stroke
				(width 0.1)
				(type default)
			)
			(layer "F.Fab")
		)
		(fp_line
			(start -0.12065 -0.305054)
			(end -0.12065 -0.2794)
			(stroke
				(width 0.1)
				(type default)
			)
			(layer "F.Fab")
		)
		(fp_line
			(start -0.12065 -0.2794)
			(end 0.12065 -0.2794)
			(stroke
				(width 0.1)
				(type default)
			)
			(layer "F.Fab")
		)
		(fp_line
			(start -0.12065 0.2794)
			(end -0.12065 0.3048)
			(stroke
				(width 0.1)
				(type default)
			)
			(layer "F.Fab")
		)
		(fp_line
			(start -0.12065 0.3048)
			(end -0.67945 0.3048)
			(stroke
				(width 0.1)
				(type default)
			)
			(layer "F.Fab")
		)
		(fp_line
			(start 0.120396 0.2794)
			(end -0.12065 0.2794)
			(stroke
				(width 0.1)
				(type default)
			)
			(layer "F.Fab")
		)
		(fp_line
			(start 0.120396 0.3048)
			(end 0.120396 0.2794)
			(stroke
				(width 0.1)
				(type default)
			)
			(layer "F.Fab")
		)
		(fp_line
			(start 0.12065 -0.3048)
			(end 0.67945 -0.3048)
			(stroke
				(width 0.1)
				(type default)
			)
			(layer "F.Fab")
		)
		(fp_line
			(start 0.12065 -0.2794)
			(end 0.12065 -0.3048)
			(stroke
				(width 0.1)
				(type default)
			)
			(layer "F.Fab")
		)
		(fp_line
			(start 0.67945 -0.3048)
			(end 0.67945 0.3048)
			(stroke
				(width 0.1)
				(type default)
			)
			(layer "F.Fab")
		)
		(fp_line
			(start 0.67945 0.3048)
			(end 0.120396 0.3048)
			(stroke
				(width 0.1)
				(type default)
			)
			(layer "F.Fab")
		)
		(pad "1" smd circle
			(at -0.40005 0)
			(size 0 0)
			(layers "F.Cu" "F.Mask" "F.Paste")
			(net "PVDD11_S3_P0_VINSEN")
		)
		(pad "2" smd circle
			(at 0.40005 0)
			(size 0 0)
			(layers "F.Cu" "F.Mask" "F.Paste")
			(net "GND")
		)
	)
	(footprint ""
		(layer "F.Cu")
		(at 225.420428 -271.407382)
		(property "Reference" "PL6503"
			(at 1.147572 3.337052 0)
			(unlocked yes)
			(layer "F.SilkS")
			(effects
				(font
					(size 0.7874 0.5842)
					(thickness 0.1524)
				)
				(justify left)
			)
		)
		(property "Value" ""
			(at 0 0 0)
			(layer "F.Fab")
			(effects
				(font
					(size 1.27 1.27)
				)
			)
		)
		(duplicate_pad_numbers_are_jumpers no)
		(fp_line
			(start -2.249932 -2.249932)
			(end 2.249932 -2.249932)
			(stroke
				(width 0.1524)
				(type default)
			)
			(layer "F.SilkS")
		)
		(fp_line
			(start -2.249932 -1.3843)
			(end -2.249932 -2.249932)
			(stroke
				(width 0.1524)
				(type default)
			)
			(layer "F.SilkS")
		)
		(fp_line
			(start -2.249932 2.249932)
			(end -2.249932 1.3843)
			(stroke
				(width 0.1524)
				(type default)
			)
			(layer "F.SilkS")
		)
		(fp_line
			(start 2.249932 -2.249932)
			(end 2.249932 -1.3843)
			(stroke
				(width 0.1524)
				(type default)
			)
			(layer "F.SilkS")
		)
		(fp_line
			(start 2.249932 1.3843)
			(end 2.249932 2.249932)
			(stroke
				(width 0.1524)
				(type default)
			)
			(layer "F.SilkS")
		)
		(fp_line
			(start 2.249932 2.249932)
			(end -2.249932 2.249932)
			(stroke
				(width 0.1524)
				(type default)
			)
			(layer "F.SilkS")
		)
		(fp_line
			(start -2.249932 -2.249932)
			(end 2.249932 -2.249932)
			(stroke
				(width 0.1)
				(type default)
			)
			(layer "F.Fab")
		)
		(fp_line
			(start -2.249932 2.249932)
			(end -2.249932 -2.249932)
			(stroke
				(width 0.1)
				(type default)
			)
			(layer "F.Fab")
		)
		(fp_line
			(start 2.249932 -2.249932)
			(end 2.249932 2.249932)
			(stroke
				(width 0.1)
				(type default)
			)
			(layer "F.Fab")
		)
		(fp_line
			(start 2.249932 2.249932)
			(end -2.249932 2.249932)
			(stroke
				(width 0.1)
				(type default)
			)
			(layer "F.Fab")
		)
		(pad "1" smd rect
			(at -1.82499 0)
			(size 1.0668 2.5146)
			(layers "F.Cu" "F.Mask" "F.Paste")
			(net "P12V_AUX")
		)
		(pad "2" smd rect
			(at 1.82499 0)
			(size 1.0668 2.5146)
			(layers "F.Cu" "F.Mask" "F.Paste")
			(net "SW_P12V_AUX_P1V8_RETIMER_CPU1_FLT")
		)
	)
	(footprint ""
		(layer "F.Cu")
		(at 157.995366 -56.331358)
		(property "Reference" "C2013"
			(at 0 0 0)
			(layer "F.SilkS")
			(hide yes)
			(effects
				(font
					(size 1.27 1.27)
				)
			)
		)
		(property "Value" ""
			(at 0 0 0)
			(layer "F.Fab")
			(effects
				(font
					(size 1.27 1.27)
				)
			)
		)
		(duplicate_pad_numbers_are_jumpers no)
		(fp_line
			(start -0.7874 -0.4064)
			(end 0.7874 -0.4064)
			(stroke
				(width 0.1524)
				(type default)
			)
			(layer "F.SilkS")
		)
		(fp_line
			(start -0.7874 0.4064)
			(end -0.7874 -0.4064)
			(stroke
				(width 0.1524)
				(type default)
			)
			(layer "F.SilkS")
		)
		(fp_line
			(start 0.7874 -0.4064)
			(end 0.7874 0.4064)
			(stroke
				(width 0.1524)
				(type default)
			)
			(layer "F.SilkS")
		)
		(fp_line
			(start 0.7874 0.4064)
			(end -0.7874 0.4064)
			(stroke
				(width 0.1524)
				(type default)
			)
			(layer "F.SilkS")
		)
		(fp_line
			(start -0.67945 -0.305054)
			(end -0.12065 -0.305054)
			(stroke
				(width 0.1)
				(type default)
			)
			(layer "F.Fab")
		)
		(fp_line
			(start -0.67945 0.3048)
			(end -0.67945 -0.305054)
			(stroke
				(width 0.1)
				(type default)
			)
			(layer "F.Fab")
		)
		(fp_line
			(start -0.12065 -0.305054)
			(end -0.12065 -0.2794)
			(stroke
				(width 0.1)
				(type default)
			)
			(layer "F.Fab")
		)
		(fp_line
			(start -0.12065 -0.2794)
			(end 0.12065 -0.2794)
			(stroke
				(width 0.1)
				(type default)
			)
			(layer "F.Fab")
		)
		(fp_line
			(start -0.12065 0.2794)
			(end -0.12065 0.3048)
			(stroke
				(width 0.1)
				(type default)
			)
			(layer "F.Fab")
		)
		(fp_line
			(start -0.12065 0.3048)
			(end -0.67945 0.3048)
			(stroke
				(width 0.1)
				(type default)
			)
			(layer "F.Fab")
		)
		(fp_line
			(start 0.120396 0.2794)
			(end -0.12065 0.2794)
			(stroke
				(width 0.1)
				(type default)
			)
			(layer "F.Fab")
		)
		(fp_line
			(start 0.120396 0.3048)
			(end 0.120396 0.2794)
			(stroke
				(width 0.1)
				(type default)
			)
			(layer "F.Fab")
		)
		(fp_line
			(start 0.12065 -0.3048)
			(end 0.67945 -0.3048)
			(stroke
				(width 0.1)
				(type default)
			)
			(layer "F.Fab")
		)
		(fp_line
			(start 0.12065 -0.2794)
			(end 0.12065 -0.3048)
			(stroke
				(width 0.1)
				(type default)
			)
			(layer "F.Fab")
		)
		(fp_line
			(start 0.67945 -0.3048)
			(end 0.67945 0.3048)
			(stroke
				(width 0.1)
				(type default)
			)
			(layer "F.Fab")
		)
		(fp_line
			(start 0.67945 0.3048)
			(end 0.120396 0.3048)
			(stroke
				(width 0.1)
				(type default)
			)
			(layer "F.Fab")
		)
		(pad "1" smd circle
			(at -0.40005 0)
			(size 0 0)
			(layers "F.Cu" "F.Mask" "F.Paste")
			(net "P3V3_AUX")
		)
		(pad "2" smd circle
			(at 0.40005 0)
			(size 0 0)
			(layers "F.Cu" "F.Mask" "F.Paste")
			(net "GND")
		)
	)
)
